# T6G (Grand Teton) — schematic netlist excerpt (pin names and nets, part order shuffled) for the footprints in the layout excerpt that follows; sources: Cadence DE-HDL packaged netlist, KiCad conversion of 04192023_DAF0TMB3IC0_F0TG_MB_C_brd_V02_OCP.brd

C6638  Q_CAP_DIFFBUS  DIFF BUS_0.22UF 6.3V 20% X6S  pkg C0201  page 319 : \1\ = P5E_CPU1_P0_TX_BUF_C_DN<4> ; \2\ = P5E_CPU1_P0_TX_BUF_DN<4>
PC803  Q_CAPP  390UF 2.5V 20% ALUM  pkg SMLF  page 225 : A = PVDD11_S3_P1 ; B = GND
R4551  Q_RES  54.9K 1% EMPTY  pkg 0402LF  page 241 : A = P3V3_AUX ; B = HPDB_HSC_PWRGD

(kicad_pcb
	(version 20260206)
	(generator "pcbnew")
	(generator_version "10.0")
	(general
		(thickness 1.6)
		(legacy_teardrops no)
	)
	(paper "A4")
	(title_block
		(title "04192023_DAF0TMB3IC0_F0TG_MB_C_brd_V02_OCP.brd")
		(comment 1 "Grand Teton / footprints 164-166 of 8354")
	)
	(layers
		(0 "F.Cu" signal "TOP")
		(4 "In1.Cu" signal "GND")
		(6 "In2.Cu" signal "IN1")
		(8 "In3.Cu" signal "GND1")
		(10 "In4.Cu" signal "IN2")
		(12 "In5.Cu" signal "GND2")
		(14 "In6.Cu" signal "IN3")
		(16 "In7.Cu" signal "GND3")
		(18 "In8.Cu" signal "VCC")
		(20 "In9.Cu" signal "VCC1")
		(22 "In10.Cu" signal "GND4")
		(24 "In11.Cu" signal "IN4")
		(26 "In12.Cu" signal "GND5")
		(28 "In13.Cu" signal "IN5")
		(30 "In14.Cu" signal "GND6")
		(32 "In15.Cu" signal "IN6")
		(34 "In16.Cu" signal "GND7")
		(2 "B.Cu" signal "BOTTOM")
		(9 "F.Adhes" user "F.Adhesive")
		(11 "B.Adhes" user "B.Adhesive")
		(13 "F.Paste" user "Package Geometry/Pastemask Top")
		(15 "B.Paste" user "Package Geometry/Pastemask Bottom")
		(5 "F.SilkS" user "Ref Des/Silkscreen Top")
		(7 "B.SilkS" user "Ref Des/Silkscreen Bottom")
		(1 "F.Mask" user "Board Geometry/Soldermask Top")
		(3 "B.Mask" user "Board Geometry/Soldermask Bottom")
		(17 "Dwgs.User" user "User.Drawings")
		(19 "Cmts.User" user "User.Comments")
		(21 "Eco1.User" user "User.Eco1")
		(23 "Eco2.User" user "User.Eco2")
		(25 "Edge.Cuts" user "Board Geometry/Outline")
		(27 "Margin" user)
		(31 "F.CrtYd" user "Package Geometry/Place Bound Top")
		(29 "B.CrtYd" user "Package Geometry/Place Bound Bottom")
		(35 "F.Fab" user "Ref Des/Assembly Top")
		(33 "B.Fab" user "Ref Des/Assembly Bottom")
	)
	(footprint ""
		(layer "F.Cu")
		(at 175.961294 -332.734412 -90)
		(property "Reference" "PC803"
			(at -4.13512 4.721352 90)
			(unlocked yes)
			(layer "F.SilkS")
			(effects
				(font
					(size 0.7874 0.5842)
					(thickness 0.1524)
				)
				(justify left)
			)
		)
		(property "Value" ""
			(at 0 0 270)
			(layer "F.Fab")
			(effects
				(font
					(size 1.27 1.27)
				)
			)
		)
		(duplicate_pad_numbers_are_jumpers no)
		(fp_line
			(start -1.988058 2.750058)
			(end 2.750058 2.750058)
			(stroke
				(width 0.1524)
				(type default)
			)
			(layer "F.SilkS")
		)
		(fp_line
			(start 2.750058 2.750058)
			(end 2.750058 0.9398)
			(stroke
				(width 0.1524)
				(type default)
			)
			(layer "F.SilkS")
		)
		(fp_line
			(start -2.750058 1.988058)
			(end -1.988058 2.750058)
			(stroke
				(width 0.1524)
				(type default)
			)
			(layer "F.SilkS")
		)
		(fp_line
			(start -2.750058 0.9398)
			(end -2.750058 1.988058)
			(stroke
				(width 0.1524)
				(type default)
			)
			(layer "F.SilkS")
		)
		(fp_line
			(start 2.750058 -0.9398)
			(end 2.750058 -2.750058)
			(stroke
				(width 0.1524)
				(type default)
			)
			(layer "F.SilkS")
		)
		(fp_line
			(start -2.750058 -1.988058)
			(end -2.750058 -0.9398)
			(stroke
				(width 0.1524)
				(type default)
			)
			(layer "F.SilkS")
		)
		(fp_line
			(start -1.988058 -2.750058)
			(end -2.750058 -1.988058)
			(stroke
				(width 0.1524)
				(type default)
			)
			(layer "F.SilkS")
		)
		(fp_line
			(start 2.750058 -2.750058)
			(end -1.988058 -2.750058)
			(stroke
				(width 0.1524)
				(type default)
			)
			(layer "F.SilkS")
		)
		(fp_line
			(start -2.750058 2.750058)
			(end 2.750058 2.750058)
			(stroke
				(width 0.1)
				(type default)
			)
			(layer "F.Fab")
		)
		(fp_line
			(start 2.750058 2.750058)
			(end 2.750058 -2.750058)
			(stroke
				(width 0.1)
				(type default)
			)
			(layer "F.Fab")
		)
		(fp_line
			(start -2.750058 -2.750058)
			(end -2.750058 2.750058)
			(stroke
				(width 0.1)
				(type default)
			)
			(layer "F.Fab")
		)
		(fp_line
			(start 2.750058 -2.750058)
			(end -2.750058 -2.750058)
			(stroke
				(width 0.1)
				(type default)
			)
			(layer "F.Fab")
		)
		(pad "1" smd rect
			(at -2.199894 0)
			(size 1.6002 3.0226)
			(layers "F.Cu" "F.Mask" "F.Paste")
			(net "PVDD11_S3_P1")
		)
		(pad "2" smd rect
			(at 2.199894 0)
			(size 1.6002 3.0226)
			(layers "F.Cu" "F.Mask" "F.Paste")
			(net "GND")
		)
	)
	(footprint ""
		(layer "F.Cu")
		(at 279.022556 -438.001664 -90)
		(property "Reference" "R4551"
			(at 0 0 270)
			(layer "F.SilkS")
			(hide yes)
			(effects
				(font
					(size 1.27 1.27)
				)
			)
		)
		(property "Value" ""
			(at 0 0 270)
			(layer "F.Fab")
			(effects
				(font
					(size 1.27 1.27)
				)
			)
		)
		(duplicate_pad_numbers_are_jumpers no)
		(fp_line
			(start -0.7874 0.4064)
			(end -0.7874 -0.4064)
			(stroke
				(width 0.1524)
				(type default)
			)
			(layer "F.SilkS")
		)
		(fp_line
			(start 0.7874 0.4064)
			(end -0.7874 0.4064)
			(stroke
				(width 0.1524)
				(type default)
			)
			(layer "F.SilkS")
		)
		(fp_line
			(start -0.7874 -0.4064)
			(end 0.7874 -0.4064)
			(stroke
				(width 0.1524)
				(type default)
			)
			(layer "F.SilkS")
		)
		(fp_line
			(start 0.7874 -0.4064)
			(end 0.7874 0.4064)
			(stroke
				(width 0.1524)
				(type default)
			)
			(layer "F.SilkS")
		)
		(fp_line
			(start -0.67945 0.3048)
			(end -0.67945 -0.305054)
			(stroke
				(width 0.1)
				(type default)
			)
			(layer "F.Fab")
		)
		(fp_line
			(start -0.12065 0.3048)
			(end -0.67945 0.3048)
			(stroke
				(width 0.1)
				(type default)
			)
			(layer "F.Fab")
		)
		(fp_line
			(start 0.120396 0.3048)
			(end 0.120396 0.2794)
			(stroke
				(width 0.1)
				(type default)
			)
			(layer "F.Fab")
		)
		(fp_line
			(start 0.67945 0.3048)
			(end 0.120396 0.3048)
			(stroke
				(width 0.1)
				(type default)
			)
			(layer "F.Fab")
		)
		(fp_line
			(start -0.12065 0.2794)
			(end -0.12065 0.3048)
			(stroke
				(width 0.1)
				(type default)
			)
			(layer "F.Fab")
		)
		(fp_line
			(start 0.120396 0.2794)
			(end -0.12065 0.2794)
			(stroke
				(width 0.1)
				(type default)
			)
			(layer "F.Fab")
		)
		(fp_line
			(start -0.12065 -0.2794)
			(end 0.12065 -0.2794)
			(stroke
				(width 0.1)
				(type default)
			)
			(layer "F.Fab")
		)
		(fp_line
			(start 0.12065 -0.2794)
			(end 0.12065 -0.3048)
			(stroke
				(width 0.1)
				(type default)
			)
			(layer "F.Fab")
		)
		(fp_line
			(start 0.12065 -0.3048)
			(end 0.67945 -0.3048)
			(stroke
				(width 0.1)
				(type default)
			)
			(layer "F.Fab")
		)
		(fp_line
			(start 0.67945 -0.3048)
			(end 0.67945 0.3048)
			(stroke
				(width 0.1)
				(type default)
			)
			(layer "F.Fab")
		)
		(fp_line
			(start -0.67945 -0.305054)
			(end -0.12065 -0.305054)
			(stroke
				(width 0.1)
				(type default)
			)
			(layer "F.Fab")
		)
		(fp_line
			(start -0.12065 -0.305054)
			(end -0.12065 -0.2794)
			(stroke
				(width 0.1)
				(type default)
			)
			(layer "F.Fab")
		)
		(pad "1" smd circle
			(at -0.40005 0 270)
			(size 0 0)
			(layers "F.Cu" "F.Mask" "F.Paste")
			(net "P3V3_AUX")
		)
		(pad "2" smd circle
			(at 0.40005 0 270)
			(size 0 0)
			(layers "F.Cu" "F.Mask" "F.Paste")
			(net "HPDB_HSC_PWRGD")
		)
	)
	(footprint ""
		(layer "F.Cu")
		(at 60.021724 -408.517344 -90)
		(property "Reference" "C6638"
			(at 0 0 270)
			(layer "F.SilkS")
			(hide yes)
			(effects
				(font
					(size 1.27 1.27)
				)
			)
		)
		(property "Value" ""
			(at 0 0 270)
			(layer "F.Fab")
			(effects
				(font
					(size 1.27 1.27)
				)
			)
		)
		(duplicate_pad_numbers_are_jumpers no)
		(fp_line
			(start -0.299974 0.150114)
			(end -0.299974 -0.150114)
			(stroke
				(width 0.1)
				(type default)
			)
			(layer "F.Fab")
		)
		(fp_line
			(start 0.299974 0.150114)
			(end -0.299974 0.150114)
			(stroke
				(width 0.1)
				(type default)
			)
			(layer "F.Fab")
		)
		(fp_line
			(start -0.299974 -0.150114)
			(end 0.299974 -0.150114)
			(stroke
				(width 0.1)
				(type default)
			)
			(layer "F.Fab")
		)
		(fp_line
			(start 0.299974 -0.150114)
			(end 0.299974 0.150114)
			(stroke
				(width 0.1)
				(type default)
			)
			(layer "F.Fab")
		)
		(pad "1" smd rect
			(at -0.2667 0 270)
			(size 0.3048 0.381)
			(layers "F.Cu" "F.Mask" "F.Paste")
			(net "P5E_CPU1_P0_TX_BUF_C_DN<4>")
		)
		(pad "2" smd rect
			(at 0.2667 0 270)
			(size 0.3048 0.381)
			(layers "F.Cu" "F.Mask" "F.Paste")
			(net "P5E_CPU1_P0_TX_BUF_DN<4>")
		)
	)
)
